# TIMECARD (Time Appliance Project (Time Card)) — schematic netlist excerpt (pin names and nets, part order shuffled) for the footprints in the layout excerpt that follows; sources: Cadence DE-HDL packaged netlist, KiCad conversion of R4006-B0001-02_R01.brd

Q3  POWERMOS_3P_PCH  pkg SOT23_V1_H045  page 21
  G  = UNNAMED_527_POWERMOS3PNCHV1_I23
  S  = XP5R0V_MAC
  D  = UNNAMED_527_FUSE_I244_1

(kicad_pcb
	(version 20260206)
	(generator "pcbnew")
	(generator_version "10.0")
	(general
		(thickness 1.6)
		(legacy_teardrops no)
	)
	(paper "A4")
	(title_block
		(title "timecard-production-celestica-r4006 — R4006-B0001-02_R01.brd")
		(comment 1 "Time Appliance Project (Time Card) / footprints 986-986 of 1113")
	)
	(layers
		(0 "F.Cu" signal "TOP")
		(4 "In1.Cu" signal "L02_GND1")
		(6 "In2.Cu" signal "L03_SIG1")
		(8 "In3.Cu" signal "L04_GND2")
		(10 "In4.Cu" signal "L05_VCC1")
		(12 "In5.Cu" signal "L06_VCC2")
		(14 "In6.Cu" signal "L07_GND3")
		(16 "In7.Cu" signal "L08_SIG2")
		(18 "In8.Cu" signal "L09_GND4")
		(2 "B.Cu" signal "BOTTOM")
		(9 "F.Adhes" user "F.Adhesive")
		(11 "B.Adhes" user "B.Adhesive")
		(13 "F.Paste" user "Package Geometry/Pastemask Top")
		(15 "B.Paste" user "Package Geometry/Pastemask Bottom")
		(5 "F.SilkS" user "Ref Des/Silkscreen Top")
		(7 "B.SilkS" user "Ref Des/Silkscreen Bottom")
		(1 "F.Mask" user "Board Geometry/Soldermask Top")
		(3 "B.Mask" user "Board Geometry/Soldermask Bottom")
		(17 "Dwgs.User" user "User.Drawings")
		(19 "Cmts.User" user "User.Comments")
		(21 "Eco1.User" user "User.Eco1")
		(23 "Eco2.User" user "User.Eco2")
		(25 "Edge.Cuts" user "Board Geometry/Outline")
		(27 "Margin" user)
		(31 "F.CrtYd" user "Package Geometry/Place Bound Top")
		(29 "B.CrtYd" user "Package Geometry/Place Bound Bottom")
		(35 "F.Fab" user "Ref Des/Assembly Top")
		(33 "B.Fab" user "Ref Des/Assembly Bottom")
	)
	(footprint ""
		(layer "B.Cu")
		(at 76.581 -58.801 -90)
		(property "Reference" "Q3"
			(at -2.413 -5.16763 270)
			(unlocked yes)
			(layer "B.SilkS")
			(effects
				(font
					(size 0.7874 0.5842)
					(thickness 0.1524)
				)
				(justify mirror)
			)
		)
		(property "Value" ""
			(at 0 0 90)
			(layer "B.Fab")
			(effects
				(font
					(size 1.27 1.27)
				)
				(justify mirror)
			)
		)
		(property "User Part Number" "PARTNUM*"
			(at -5.207254 -0.501904 270)
			(unlocked yes)
			(layer "Cmts.User")
			(hide yes)
			(effects
				(font
					(size 0.7874 0.5842)
					(thickness 0.000001)
				)
				(justify mirror)
			)
		)
		(property "Device Type" "POWERMOS_3P_PCH-G121-10216-01"
			(at -3.642614 -1.544828 270)
			(unlocked yes)
			(layer "B.Fab")
			(hide yes)
			(effects
				(font
					(size 0.7874 0.5842)
					(thickness 0.000001)
				)
				(justify mirror)
			)
		)
		(duplicate_pad_numbers_are_jumpers no)
		(fp_line
			(start -1.7018 2.0574)
			(end -0.1905 2.0574)
			(stroke
				(width 0.1)
				(type default)
			)
			(layer "B.SilkS")
		)
		(fp_line
			(start -0.1905 2.0574)
			(end -0.1905 0.9144)
			(stroke
				(width 0.1)
				(type default)
			)
			(layer "B.SilkS")
		)
		(fp_line
			(start 0.1905 2.0574)
			(end 1.7018 2.0574)
			(stroke
				(width 0.1)
				(type default)
			)
			(layer "B.SilkS")
		)
		(fp_line
			(start 1.7018 2.0574)
			(end 1.7018 -0.9144)
			(stroke
				(width 0.1)
				(type default)
			)
			(layer "B.SilkS")
		)
		(fp_line
			(start -0.1905 0.9144)
			(end 0.1905 0.9144)
			(stroke
				(width 0.1)
				(type default)
			)
			(layer "B.SilkS")
		)
		(fp_line
			(start 0.1905 0.9144)
			(end 0.1905 2.0574)
			(stroke
				(width 0.1)
				(type default)
			)
			(layer "B.SilkS")
		)
		(fp_line
			(start -1.7018 -0.9144)
			(end -1.7018 2.0574)
			(stroke
				(width 0.1)
				(type default)
			)
			(layer "B.SilkS")
		)
		(fp_line
			(start -0.7493 -0.9144)
			(end -1.7018 -0.9144)
			(stroke
				(width 0.1)
				(type default)
			)
			(layer "B.SilkS")
		)
		(fp_line
			(start 0.7493 -0.9144)
			(end 0.7493 -2.0574)
			(stroke
				(width 0.1)
				(type default)
			)
			(layer "B.SilkS")
		)
		(fp_line
			(start 1.7018 -0.9144)
			(end 0.7493 -0.9144)
			(stroke
				(width 0.1)
				(type default)
			)
			(layer "B.SilkS")
		)
		(fp_line
			(start -0.7493 -2.0574)
			(end -0.7493 -0.9144)
			(stroke
				(width 0.1)
				(type default)
			)
			(layer "B.SilkS")
		)
		(fp_line
			(start 0.7493 -2.0574)
			(end -0.7493 -2.0574)
			(stroke
				(width 0.1)
				(type default)
			)
			(layer "B.SilkS")
		)
		(fp_poly
			(pts
				(arc
					(start 1.524 2.413)
					(mid 1.524 3.175)
					(end 1.524 2.413)
				)
			)
			(stroke
				(width 0)
				(type default)
			)
			(fill yes)
			(layer "B.SilkS")
		)
		(fp_poly
			(pts
				(xy 1.7018 2.0828) (xy 1.7018 -0.9144) (xy 0.762 -0.9144) (xy 0.762 -2.0574) (xy -0.762 -2.0574)
				(xy -0.762 -0.9144) (xy -1.7018 -0.9144) (xy -1.7018 2.0828)
			)
			(stroke
				(width 0)
				(type default)
			)
			(fill no)
			(layer "B.CrtYd")
		)
		(fp_line
			(start -1.1684 1.143)
			(end -0.7112 1.143)
			(stroke
				(width 0.1)
				(type default)
			)
			(layer "B.Fab")
		)
		(fp_line
			(start -0.7112 1.143)
			(end -0.7112 0.6604)
			(stroke
				(width 0.1)
				(type default)
			)
			(layer "B.Fab")
		)
		(fp_line
			(start 0.7112 1.143)
			(end 1.1684 1.143)
			(stroke
				(width 0.1)
				(type default)
			)
			(layer "B.Fab")
		)
		(fp_line
			(start 1.1684 1.143)
			(end 1.1684 0.6604)
			(stroke
				(width 0.1)
				(type default)
			)
			(layer "B.Fab")
		)
		(fp_line
			(start -0.7112 0.9144)
			(end -1.1684 0.9144)
			(stroke
				(width 0.1)
				(type default)
			)
			(layer "B.Fab")
		)
		(fp_line
			(start 1.1684 0.9144)
			(end 0.7112 0.9144)
			(stroke
				(width 0.1)
				(type default)
			)
			(layer "B.Fab")
		)
		(fp_line
			(start -1.4478 0.6604)
			(end 1.4478 0.6604)
			(stroke
				(width 0.1)
				(type default)
			)
			(layer "B.Fab")
		)
		(fp_line
			(start -1.1684 0.6604)
			(end -1.1684 1.143)
			(stroke
				(width 0.1)
				(type default)
			)
			(layer "B.Fab")
		)
		(fp_line
			(start -0.7112 0.6604)
			(end -1.1684 0.6604)
			(stroke
				(width 0.1)
				(type default)
			)
			(layer "B.Fab")
		)
		(fp_line
			(start 0.7112 0.6604)
			(end 0.7112 1.143)
			(stroke
				(width 0.1)
				(type default)
			)
			(layer "B.Fab")
		)
		(fp_line
			(start 1.1684 0.6604)
			(end 0.7112 0.6604)
			(stroke
				(width 0.1)
				(type default)
			)
			(layer "B.Fab")
		)
		(fp_line
			(start 1.4478 0.6604)
			(end 1.3716 0.5842)
			(stroke
				(width 0.1)
				(type default)
			)
			(layer "B.Fab")
		)
		(fp_line
			(start 1.4478 0.6604)
			(end 1.4478 -0.6604)
			(stroke
				(width 0.1)
				(type default)
			)
			(layer "B.Fab")
		)
		(fp_line
			(start -1.3716 0.5842)
			(end -1.4478 0.6604)
			(stroke
				(width 0.1)
				(type default)
			)
			(layer "B.Fab")
		)
		(fp_line
			(start -1.3716 0.5842)
			(end 1.3716 0.5842)
			(stroke
				(width 0.1)
				(type default)
			)
			(layer "B.Fab")
		)
		(fp_line
			(start 1.3716 0.5842)
			(end 1.3716 -0.5842)
			(stroke
				(width 0.1)
				(type default)
			)
			(layer "B.Fab")
		)
		(fp_line
			(start -1.3716 -0.5842)
			(end -1.3716 0.5842)
			(stroke
				(width 0.1)
				(type default)
			)
			(layer "B.Fab")
		)
		(fp_line
			(start -1.3716 -0.5842)
			(end -1.4478 -0.6604)
			(stroke
				(width 0.1)
				(type default)
			)
			(layer "B.Fab")
		)
		(fp_line
			(start 1.3716 -0.5842)
			(end -1.3716 -0.5842)
			(stroke
				(width 0.1)
				(type default)
			)
			(layer "B.Fab")
		)
		(fp_line
			(start -1.4478 -0.6604)
			(end -1.4478 0.6604)
			(stroke
				(width 0.1)
				(type default)
			)
			(layer "B.Fab")
		)
		(fp_line
			(start -0.2286 -0.6604)
			(end 0.2286 -0.6604)
			(stroke
				(width 0.1)
				(type default)
			)
			(layer "B.Fab")
		)
		(fp_line
			(start 0.2286 -0.6604)
			(end 0.2286 -1.143)
			(stroke
				(width 0.1)
				(type default)
			)
			(layer "B.Fab")
		)
		(fp_line
			(start 1.4478 -0.6604)
			(end 1.3716 -0.5842)
			(stroke
				(width 0.1)
				(type default)
			)
			(layer "B.Fab")
		)
		(fp_line
			(start 1.4478 -0.6604)
			(end -1.4478 -0.6604)
			(stroke
				(width 0.1)
				(type default)
			)
			(layer "B.Fab")
		)
		(fp_line
			(start 0.2286 -0.9144)
			(end -0.2286 -0.9144)
			(stroke
				(width 0.1)
				(type default)
			)
			(layer "B.Fab")
		)
		(fp_line
			(start -0.2286 -1.143)
			(end -0.2286 -0.6604)
			(stroke
				(width 0.1)
				(type default)
			)
			(layer "B.Fab")
		)
		(fp_line
			(start 0.2286 -1.143)
			(end -0.2286 -1.143)
			(stroke
				(width 0.1)
				(type default)
			)
			(layer "B.Fab")
		)
		(fp_poly
			(pts
				(arc
					(start 1.651 1.27)
					(mid 1.651 2.032)
					(end 1.651 1.27)
				)
			)
			(stroke
				(width 0)
				(type default)
			)
			(fill yes)
			(layer "B.Fab")
		)
		(fp_text user "2"
			(at -1.8288 1.30175 270)
			(unlocked yes)
			(layer "B.SilkS")
			(effects
				(font
					(size 0.635 0.4064)
					(thickness 0.1524)
				)
				(justify left mirror)
			)
		)
		(fp_text user "2"
			(at -1.23063 1.4859 0)
			(unlocked yes)
			(layer "B.Fab")
			(effects
				(font
					(size 0.7874 0.5842)
					(thickness 0.1524)
				)
				(justify left mirror)
			)
		)
		(pad "1" smd rect
			(at 0.9398 1.1049 90)
			(size 0.9906 1.397)
			(layers "B.Cu" "B.Mask" "B.Paste")
			(net "UNNAMED_527_POWERMOS3PNCHV1_I23")
		)
		(pad "2" smd rect
			(at -0.9398 1.1049 90)
			(size 0.9906 1.397)
			(layers "B.Cu" "B.Mask" "B.Paste")
			(net "XP5R0V_MAC")
		)
		(pad "3" smd rect
			(at 0 -1.1049 90)
			(size 0.9906 1.397)
			(layers "B.Cu" "B.Mask" "B.Paste")
			(net "UNNAMED_527_FUSE_I244_1")
		)
	)
)
